(kicad_pcb
	(version 20260206)
	(generator "pcbnew")
	(generator_version "10.0")
	(general
		(thickness 1.6)
		(legacy_teardrops no)
	)
	(paper "A4")
	(title_block
		(title "03242023_DA0F0TMBIJ0_F0T_Motherboard_J_brd_V01_OCP.brd")
		(comment 1 "Grand Teton / footprint 1682 of 6105 (U1), pads 1493-1601 of 4677")
	)
	(layers
		(0 "F.Cu" signal "TOP")
		(4 "In1.Cu" signal "GND")
		(6 "In2.Cu" signal "IN1")
		(8 "In3.Cu" signal "GND1")
		(10 "In4.Cu" signal "IN2")
		(12 "In5.Cu" signal "GND2")
		(14 "In6.Cu" signal "IN3")
		(16 "In7.Cu" signal "GND3")
		(18 "In8.Cu" signal "VCC")
		(20 "In9.Cu" signal "VCC1")
		(22 "In10.Cu" signal "GND4")
		(24 "In11.Cu" signal "IN4")
		(26 "In12.Cu" signal "GND5")
		(28 "In13.Cu" signal "IN5")
		(30 "In14.Cu" signal "GND6")
		(32 "In15.Cu" signal "IN6")
		(34 "In16.Cu" signal "GND7")
		(2 "B.Cu" signal "BOTTOM")
		(9 "F.Adhes" user "F.Adhesive")
		(11 "B.Adhes" user "B.Adhesive")
		(13 "F.Paste" user "Package Geometry/Pastemask Top")
		(15 "B.Paste" user "Package Geometry/Pastemask Bottom")
		(5 "F.SilkS" user "Ref Des/Silkscreen Top")
		(7 "B.SilkS" user "Ref Des/Silkscreen Bottom")
		(1 "F.Mask" user "Board Geometry/Soldermask Top")
		(3 "B.Mask" user "Board Geometry/Soldermask Bottom")
		(17 "Dwgs.User" user "User.Drawings")
		(19 "Cmts.User" user "User.Comments")
		(21 "Eco1.User" user "User.Eco1")
		(23 "Eco2.User" user "User.Eco2")
		(25 "Edge.Cuts" user "Board Geometry/Outline")
		(27 "Margin" user)
		(31 "F.CrtYd" user "Package Geometry/Place Bound Top")
		(29 "B.CrtYd" user "Package Geometry/Place Bound Bottom")
		(35 "F.Fab" user "Ref Des/Assembly Top")
		(33 "B.Fab" user "Ref Des/Assembly Bottom")
	)
	(footprint ""
		(layer "F.Cu")
		(at 111.93018 -251.76988 90)
		(property "Reference" "U1"
			(at -74.913236 41.548812 0)
			(unlocked yes)
			(layer "F.SilkS")
			(effects
				(font
					(size 1.6002 1.1938)
					(thickness 0.1524)
				)
				(justify left)
			)
		)
		(property "Value" ""
			(at 0 0 90)
			(layer "F.Fab")
			(effects
				(font
					(size 1.27 1.27)
				)
			)
		)
		(duplicate_pad_numbers_are_jumpers no)
		(pad "BU72" smd circle
			(at 21.961094 -0.649732 270)
			(size 0.4318 0.4318)
			(layers "F.Cu" "F.Mask" "F.Paste")
			(net "PVCCIN_CPU1")
		)
		(pad "BU74" smd circle
			(at 23.58898 -0.649732 270)
			(size 0.4318 0.4318)
			(layers "F.Cu" "F.Mask" "F.Paste")
			(net "PVCCIN_CPU1")
		)
		(pad "BU76" smd circle
			(at 25.216612 -0.649732 270)
			(size 0.4318 0.4318)
			(layers "F.Cu" "F.Mask" "F.Paste")
			(net "PVCCIN_CPU1")
		)
		(pad "BU78" smd circle
			(at 26.844498 -0.649732 270)
			(size 0.4318 0.4318)
			(layers "F.Cu" "F.Mask" "F.Paste")
			(net "PVCCIN_CPU1")
		)
		(pad "BU80" smd circle
			(at 28.472384 -0.649732 270)
			(size 0.4318 0.4318)
			(layers "F.Cu" "F.Mask" "F.Paste")
			(net "PVCCIN_CPU1")
		)
		(pad "BU82" smd circle
			(at 30.100016 -0.649732 270)
			(size 0.4318 0.4318)
			(layers "F.Cu" "F.Mask" "F.Paste")
			(net "PVCCIN_CPU1")
		)
		(pad "BU84" smd circle
			(at 31.727902 -0.649732 270)
			(size 0.4318 0.4318)
			(layers "F.Cu" "F.Mask" "F.Paste")
			(net "PVCCIN_CPU1")
		)
		(pad "BU86" smd circle
			(at 33.355534 -0.649732 270)
			(size 0.4318 0.4318)
			(layers "F.Cu" "F.Mask" "F.Paste")
			(net "PVCCIN_CPU1")
		)
		(pad "BU88" smd circle
			(at 34.98342 -0.649732 270)
			(size 0.4318 0.4318)
			(layers "F.Cu" "F.Mask" "F.Paste")
			(net "PVCCIN_CPU1")
		)
		(pad "BU90" smd oval
			(at 36.611306 -0.649732)
			(size 0.381 0.4826)
			(drill
				(offset 0 -0.0508)
			)
			(layers "F.Cu" "F.Mask" "F.Paste")
			(net "PVCCIN_CPU1")
		)
		(pad "BV2" smd oval
			(at -36.611306 -0.290068 180)
			(size 0.381 0.4826)
			(drill
				(offset 0 -0.0508)
			)
			(layers "F.Cu" "F.Mask" "F.Paste")
			(net "GND")
		)
		(pad "BV4" smd circle
			(at -34.98342 -0.290068 270)
			(size 0.4318 0.4318)
			(layers "F.Cu" "F.Mask" "F.Paste")
			(net "GND")
		)
		(pad "BV6" smd circle
			(at -33.355534 -0.290068 270)
			(size 0.4318 0.4318)
			(layers "F.Cu" "F.Mask" "F.Paste")
			(net "GND")
		)
		(pad "BV8" smd circle
			(at -31.727902 -0.290068 270)
			(size 0.4318 0.4318)
			(layers "F.Cu" "F.Mask" "F.Paste")
			(net "GND")
		)
		(pad "BV10" smd circle
			(at -30.100016 -0.290068 270)
			(size 0.4318 0.4318)
			(layers "F.Cu" "F.Mask" "F.Paste")
			(net "P5E_CPU1_PE1_RX_DN<8>")
		)
		(pad "BV12" smd circle
			(at -28.472384 -0.290068 270)
			(size 0.4318 0.4318)
			(layers "F.Cu" "F.Mask" "F.Paste")
			(net "GND")
		)
		(pad "BV14" smd circle
			(at -26.844498 -0.290068 270)
			(size 0.4318 0.4318)
			(layers "F.Cu" "F.Mask" "F.Paste")
			(net "P5E_CPU1_PE1_TX_DN<8>")
		)
		(pad "BV16" smd circle
			(at -25.216612 -0.290068 270)
			(size 0.4318 0.4318)
			(layers "F.Cu" "F.Mask" "F.Paste")
			(net "GND")
		)
		(pad "BV18" smd circle
			(at -23.58898 -0.290068 270)
			(size 0.4318 0.4318)
			(layers "F.Cu" "F.Mask" "F.Paste")
			(net "GND")
		)
		(pad "BV20" smd circle
			(at -21.961094 -0.290068 270)
			(size 0.4318 0.4318)
			(layers "F.Cu" "F.Mask" "F.Paste")
			(net "GND")
		)
		(pad "BV22" smd circle
			(at -20.333462 -0.290068 270)
			(size 0.4318 0.4318)
			(layers "F.Cu" "F.Mask" "F.Paste")
			(net "NC_CPU1_UPI1_APROBE<0>")
		)
		(pad "BV24" smd circle
			(at -18.705576 -0.290068 270)
			(size 0.4318 0.4318)
			(layers "F.Cu" "F.Mask" "F.Paste")
			(net "JTAG_DBP_CPU1_GTL_R_TDI")
		)
		(pad "BV26" smd circle
			(at -17.07769 -0.290068 270)
			(size 0.4318 0.4318)
			(layers "F.Cu" "F.Mask" "F.Paste")
			(net "FM_PEHPCPU1_ALERT_N")
		)
		(pad "BV28" smd circle
			(at -15.450058 -0.290068 270)
			(size 0.4318 0.4318)
			(layers "F.Cu" "F.Mask" "F.Paste")
			(net "TP_TRC_CPU1_PTI<7>")
		)
		(pad "BV30" smd circle
			(at -13.822426 -0.290068 270)
			(size 0.4318 0.4318)
			(layers "F.Cu" "F.Mask" "F.Paste")
			(net "TP_TRC_CPU1_PTI<5>")
		)
		(pad "BV32" smd circle
			(at -12.19454 -0.290068 270)
			(size 0.4318 0.4318)
			(layers "F.Cu" "F.Mask" "F.Paste")
			(net "PVCCIN_CPU1")
		)
		(pad "BV34" smd circle
			(at -10.566654 -0.290068 270)
			(size 0.4318 0.4318)
			(layers "F.Cu" "F.Mask" "F.Paste")
			(net "PVCCIN_CPU1")
		)
		(pad "BV36" smd circle
			(at -8.939022 -0.290068 270)
			(size 0.4318 0.4318)
			(layers "F.Cu" "F.Mask" "F.Paste")
			(net "PVCCIN_CPU1")
		)
		(pad "BV38" smd circle
			(at -7.311136 -0.290068 270)
			(size 0.4318 0.4318)
			(layers "F.Cu" "F.Mask" "F.Paste")
			(net "PVCCIN_CPU1")
		)
		(pad "BV40" smd circle
			(at -5.68325 -0.290068 270)
			(size 0.4318 0.4318)
			(layers "F.Cu" "F.Mask" "F.Paste")
			(net "PVCCIN_CPU1")
		)
		(pad "BV42" smd circle
			(at -4.055618 -0.290068 270)
			(size 0.4318 0.4318)
			(layers "F.Cu" "F.Mask" "F.Paste")
			(net "PVCCIN_CPU1")
		)
		(pad "BV44" smd circle
			(at -2.427732 -0.290068 270)
			(size 0.4318 0.4318)
			(layers "F.Cu" "F.Mask" "F.Paste")
			(net "PVCCIN_CPU1")
		)
		(pad "BV47" smd circle
			(at 1.613916 -0.180086 270)
			(size 0.4318 0.4318)
			(layers "F.Cu" "F.Mask" "F.Paste")
			(net "PVCCIN_CPU1")
		)
		(pad "BV49" smd circle
			(at 3.241802 -0.180086 270)
			(size 0.4318 0.4318)
			(layers "F.Cu" "F.Mask" "F.Paste")
			(net "PVCCIN_CPU1")
		)
		(pad "BV51" smd circle
			(at 4.869434 -0.180086 270)
			(size 0.4318 0.4318)
			(layers "F.Cu" "F.Mask" "F.Paste")
			(net "PVCCIN_CPU1")
		)
		(pad "BV53" smd circle
			(at 6.49732 -0.180086 270)
			(size 0.4318 0.4318)
			(layers "F.Cu" "F.Mask" "F.Paste")
			(net "PVCCIN_CPU1")
		)
		(pad "BV55" smd circle
			(at 8.124952 -0.180086 270)
			(size 0.4318 0.4318)
			(layers "F.Cu" "F.Mask" "F.Paste")
			(net "PVCCIN_CPU1")
		)
		(pad "BV57" smd circle
			(at 9.752838 -0.180086 270)
			(size 0.4318 0.4318)
			(layers "F.Cu" "F.Mask" "F.Paste")
			(net "PVCCIN_CPU1")
		)
		(pad "BV59" smd circle
			(at 11.380724 -0.180086 270)
			(size 0.4318 0.4318)
			(layers "F.Cu" "F.Mask" "F.Paste")
			(net "PVCCIN_CPU1")
		)
		(pad "BV61" smd circle
			(at 13.008356 -0.180086 270)
			(size 0.4318 0.4318)
			(layers "F.Cu" "F.Mask" "F.Paste")
			(net "PVCCIN_CPU1")
		)
		(pad "BV63" smd circle
			(at 14.635988 -0.180086 270)
			(size 0.4318 0.4318)
			(layers "F.Cu" "F.Mask" "F.Paste")
			(net "PVCCIN_CPU1")
		)
		(pad "BV65" smd circle
			(at 16.263874 -0.180086 270)
			(size 0.4318 0.4318)
			(layers "F.Cu" "F.Mask" "F.Paste")
			(net "PVCCIN_CPU1")
		)
		(pad "BV67" smd circle
			(at 17.89176 -0.180086 270)
			(size 0.4318 0.4318)
			(layers "F.Cu" "F.Mask" "F.Paste")
			(net "PVCCIN_CPU1")
		)
		(pad "BV69" smd circle
			(at 19.519392 -0.180086 270)
			(size 0.4318 0.4318)
			(layers "F.Cu" "F.Mask" "F.Paste")
			(net "PVCCIN_CPU1")
		)
		(pad "BV71" smd circle
			(at 21.147278 -0.180086 270)
			(size 0.4318 0.4318)
			(layers "F.Cu" "F.Mask" "F.Paste")
			(net "PVCCIN_CPU1")
		)
		(pad "BV73" smd circle
			(at 22.77491 -0.180086 270)
			(size 0.4318 0.4318)
			(layers "F.Cu" "F.Mask" "F.Paste")
			(net "PVCCIN_CPU1")
		)
		(pad "BV75" smd circle
			(at 24.402796 -0.180086 270)
			(size 0.4318 0.4318)
			(layers "F.Cu" "F.Mask" "F.Paste")
			(net "PVCCIN_CPU1")
		)
		(pad "BV77" smd circle
			(at 26.030682 -0.180086 270)
			(size 0.4318 0.4318)
			(layers "F.Cu" "F.Mask" "F.Paste")
			(net "PVCCIN_CPU1")
		)
		(pad "BV79" smd circle
			(at 27.658314 -0.180086 270)
			(size 0.4318 0.4318)
			(layers "F.Cu" "F.Mask" "F.Paste")
			(net "PVCCIN_CPU1")
		)
		(pad "BV81" smd circle
			(at 29.2862 -0.180086 270)
			(size 0.4318 0.4318)
			(layers "F.Cu" "F.Mask" "F.Paste")
			(net "PVCCIN_CPU1")
		)
		(pad "BV83" smd circle
			(at 30.914086 -0.180086 270)
			(size 0.4318 0.4318)
			(layers "F.Cu" "F.Mask" "F.Paste")
			(net "PVCCIN_CPU1")
		)
		(pad "BV85" smd circle
			(at 32.541718 -0.180086 270)
			(size 0.4318 0.4318)
			(layers "F.Cu" "F.Mask" "F.Paste")
			(net "PVCCIN_CPU1")
		)
		(pad "BV87" smd circle
			(at 34.169604 -0.180086 270)
			(size 0.4318 0.4318)
			(layers "F.Cu" "F.Mask" "F.Paste")
			(net "PVCCIN_CPU1")
		)
		(pad "BV89" smd circle
			(at 35.797236 -0.180086 270)
			(size 0.4318 0.4318)
			(layers "F.Cu" "F.Mask" "F.Paste")
			(net "PVCCIN_CPU1")
		)
		(pad "BW3" smd circle
			(at -35.797236 0.180086 270)
			(size 0.4318 0.4318)
			(layers "F.Cu" "F.Mask" "F.Paste")
			(net "GND")
		)
		(pad "BW5" smd circle
			(at -34.169604 0.180086 270)
			(size 0.4318 0.4318)
			(layers "F.Cu" "F.Mask" "F.Paste")
			(net "GND")
		)
		(pad "BW7" smd circle
			(at -32.541718 0.180086 270)
			(size 0.4318 0.4318)
			(layers "F.Cu" "F.Mask" "F.Paste")
			(net "UPI_CPU1_CPU0_P1P0_DP<23>")
		)
		(pad "BW9" smd circle
			(at -30.914086 0.180086 270)
			(size 0.4318 0.4318)
			(layers "F.Cu" "F.Mask" "F.Paste")
			(net "GND")
		)
		(pad "BW11" smd circle
			(at -29.2862 0.180086 270)
			(size 0.4318 0.4318)
			(layers "F.Cu" "F.Mask" "F.Paste")
			(net "P5E_CPU1_PE1_RX_DN<7>")
		)
		(pad "BW13" smd circle
			(at -27.658314 0.180086 270)
			(size 0.4318 0.4318)
			(layers "F.Cu" "F.Mask" "F.Paste")
			(net "GND")
		)
		(pad "BW15" smd circle
			(at -26.030682 0.180086 270)
			(size 0.4318 0.4318)
			(layers "F.Cu" "F.Mask" "F.Paste")
			(net "P5E_CPU1_PE1_TX_DP<8>")
		)
		(pad "BW17" smd circle
			(at -24.402796 0.180086 270)
			(size 0.4318 0.4318)
			(layers "F.Cu" "F.Mask" "F.Paste")
			(net "GND")
		)
		(pad "BW19" smd circle
			(at -22.77491 0.180086 270)
			(size 0.4318 0.4318)
			(layers "F.Cu" "F.Mask" "F.Paste")
			(net "TP_DMI_CPU1_PCH_TX_DN<0>")
		)
		(pad "BW21" smd circle
			(at -21.147278 0.180086 270)
			(size 0.4318 0.4318)
			(layers "F.Cu" "F.Mask" "F.Paste")
			(net "NC_CPU1_DMI_APROBE<1>")
		)
		(pad "BW23" smd circle
			(at -19.519392 0.180086 270)
			(size 0.4318 0.4318)
			(layers "F.Cu" "F.Mask" "F.Paste")
			(net "NC_CPU1_PE2_APROBE<1>")
		)
		(pad "BW25" smd circle
			(at -17.89176 0.180086 270)
			(size 0.4318 0.4318)
			(layers "F.Cu" "F.Mask" "F.Paste")
			(net "JTAG_CPU1_MUX_GTL_TDO")
		)
		(pad "BW27" smd circle
			(at -16.263874 0.180086 270)
			(size 0.4318 0.4318)
			(layers "F.Cu" "F.Mask" "F.Paste")
			(net "GND")
		)
		(pad "BW29" smd circle
			(at -14.635988 0.180086 270)
			(size 0.4318 0.4318)
			(layers "F.Cu" "F.Mask" "F.Paste")
			(net "GND")
		)
		(pad "BW31" smd circle
			(at -13.008356 0.180086 270)
			(size 0.4318 0.4318)
			(layers "F.Cu" "F.Mask" "F.Paste")
			(net "GND")
		)
		(pad "BW33" smd circle
			(at -11.380724 0.180086 270)
			(size 0.4318 0.4318)
			(layers "F.Cu" "F.Mask" "F.Paste")
			(net "PVCCIN_CPU1")
		)
		(pad "BW35" smd circle
			(at -9.752838 0.180086 270)
			(size 0.4318 0.4318)
			(layers "F.Cu" "F.Mask" "F.Paste")
			(net "PVCCIN_CPU1")
		)
		(pad "BW37" smd circle
			(at -8.124952 0.180086 270)
			(size 0.4318 0.4318)
			(layers "F.Cu" "F.Mask" "F.Paste")
			(net "PVCCIN_CPU1")
		)
		(pad "BW39" smd circle
			(at -6.49732 0.180086 270)
			(size 0.4318 0.4318)
			(layers "F.Cu" "F.Mask" "F.Paste")
			(net "PVCCIN_CPU1")
		)
		(pad "BW41" smd circle
			(at -4.869434 0.180086 270)
			(size 0.4318 0.4318)
			(layers "F.Cu" "F.Mask" "F.Paste")
			(net "PVCCIN_CPU1")
		)
		(pad "BW43" smd circle
			(at -3.241802 0.180086 270)
			(size 0.4318 0.4318)
			(layers "F.Cu" "F.Mask" "F.Paste")
			(net "PVCCIN_CPU1")
		)
		(pad "BW45" smd circle
			(at -1.613916 0.180086 270)
			(size 0.4318 0.4318)
			(layers "F.Cu" "F.Mask" "F.Paste")
			(net "PVCCIN_CPU1")
		)
		(pad "BW48" smd circle
			(at 2.427732 0.290068 270)
			(size 0.4318 0.4318)
			(layers "F.Cu" "F.Mask" "F.Paste")
			(net "PVCCIN_CPU1")
		)
		(pad "BW50" smd circle
			(at 4.055618 0.290068 270)
			(size 0.4318 0.4318)
			(layers "F.Cu" "F.Mask" "F.Paste")
			(net "PVCCIN_CPU1")
		)
		(pad "BW52" smd circle
			(at 5.68325 0.290068 270)
			(size 0.4318 0.4318)
			(layers "F.Cu" "F.Mask" "F.Paste")
			(net "PVCCIN_CPU1")
		)
		(pad "BW54" smd circle
			(at 7.311136 0.290068 270)
			(size 0.4318 0.4318)
			(layers "F.Cu" "F.Mask" "F.Paste")
			(net "PVCCIN_CPU1")
		)
		(pad "BW56" smd circle
			(at 8.939022 0.290068 270)
			(size 0.4318 0.4318)
			(layers "F.Cu" "F.Mask" "F.Paste")
			(net "PVCCIN_CPU1")
		)
		(pad "BW58" smd circle
			(at 10.566654 0.290068 270)
			(size 0.4318 0.4318)
			(layers "F.Cu" "F.Mask" "F.Paste")
			(net "PVCCIN_CPU1")
		)
		(pad "BW60" smd circle
			(at 12.19454 0.290068 270)
			(size 0.4318 0.4318)
			(layers "F.Cu" "F.Mask" "F.Paste")
			(net "PVCCIN_CPU1")
		)
		(pad "BW62" smd circle
			(at 13.822426 0.290068 270)
			(size 0.4318 0.4318)
			(layers "F.Cu" "F.Mask" "F.Paste")
			(net "PVCCIN_CPU1")
		)
		(pad "BW64" smd circle
			(at 15.450058 0.290068 270)
			(size 0.4318 0.4318)
			(layers "F.Cu" "F.Mask" "F.Paste")
			(net "PVCCIN_CPU1")
		)
		(pad "BW66" smd circle
			(at 17.07769 0.290068 270)
			(size 0.4318 0.4318)
			(layers "F.Cu" "F.Mask" "F.Paste")
			(net "PVCCIN_CPU1")
		)
		(pad "BW68" smd circle
			(at 18.705576 0.290068 270)
			(size 0.4318 0.4318)
			(layers "F.Cu" "F.Mask" "F.Paste")
			(net "PVCCIN_CPU1")
		)
		(pad "BW70" smd circle
			(at 20.333462 0.290068 270)
			(size 0.4318 0.4318)
			(layers "F.Cu" "F.Mask" "F.Paste")
			(net "PVCCIN_CPU1")
		)
		(pad "BW72" smd circle
			(at 21.961094 0.290068 270)
			(size 0.4318 0.4318)
			(layers "F.Cu" "F.Mask" "F.Paste")
			(net "PVCCIN_CPU1")
		)
		(pad "BW74" smd circle
			(at 23.58898 0.290068 270)
			(size 0.4318 0.4318)
			(layers "F.Cu" "F.Mask" "F.Paste")
			(net "PVCCIN_CPU1")
		)
		(pad "BW76" smd circle
			(at 25.216612 0.290068 270)
			(size 0.4318 0.4318)
			(layers "F.Cu" "F.Mask" "F.Paste")
			(net "PVCCIN_CPU1")
		)
		(pad "BW78" smd circle
			(at 26.844498 0.290068 270)
			(size 0.4318 0.4318)
			(layers "F.Cu" "F.Mask" "F.Paste")
			(net "PVCCIN_CPU1")
		)
		(pad "BW80" smd circle
			(at 28.472384 0.290068 270)
			(size 0.4318 0.4318)
			(layers "F.Cu" "F.Mask" "F.Paste")
			(net "PVCCIN_CPU1")
		)
		(pad "BW82" smd circle
			(at 30.100016 0.290068 270)
			(size 0.4318 0.4318)
			(layers "F.Cu" "F.Mask" "F.Paste")
			(net "PVCCIN_CPU1")
		)
		(pad "BW84" smd circle
			(at 31.727902 0.290068 270)
			(size 0.4318 0.4318)
			(layers "F.Cu" "F.Mask" "F.Paste")
			(net "PVCCIN_CPU1")
		)
		(pad "BW86" smd circle
			(at 33.355534 0.290068 270)
			(size 0.4318 0.4318)
			(layers "F.Cu" "F.Mask" "F.Paste")
			(net "PVCCIN_CPU1")
		)
		(pad "BW88" smd circle
			(at 34.98342 0.290068 270)
			(size 0.4318 0.4318)
			(layers "F.Cu" "F.Mask" "F.Paste")
			(net "PVCCIN_CPU1")
		)
		(pad "BW90" smd oval
			(at 36.611306 0.290068)
			(size 0.381 0.4826)
			(drill
				(offset 0 -0.0508)
			)
			(layers "F.Cu" "F.Mask" "F.Paste")
			(net "PVCCIN_CPU1")
		)
		(pad "BY2" smd oval
			(at -36.611306 0.649732 180)
			(size 0.381 0.4826)
			(drill
				(offset 0 -0.0508)
			)
			(layers "F.Cu" "F.Mask" "F.Paste")
			(net "UPI_CPU0_CPU1_P0P1_DP<23>")
		)
		(pad "BY4" smd circle
			(at -34.98342 0.649732 270)
			(size 0.4318 0.4318)
			(layers "F.Cu" "F.Mask" "F.Paste")
			(net "GND")
		)
		(pad "BY6" smd circle
			(at -33.355534 0.649732 270)
			(size 0.4318 0.4318)
			(layers "F.Cu" "F.Mask" "F.Paste")
			(net "UPI_CPU1_CPU0_P1P0_DN<23>")
		)
		(pad "BY8" smd circle
			(at -31.727902 0.649732 270)
			(size 0.4318 0.4318)
			(layers "F.Cu" "F.Mask" "F.Paste")
			(net "GND")
		)
		(pad "BY10" smd circle
			(at -30.100016 0.649732 270)
			(size 0.4318 0.4318)
			(layers "F.Cu" "F.Mask" "F.Paste")
			(net "P5E_CPU1_PE1_RX_DP<7>")
		)
		(pad "BY12" smd circle
			(at -28.472384 0.649732 270)
			(size 0.4318 0.4318)
			(layers "F.Cu" "F.Mask" "F.Paste")
			(net "GND")
		)
		(pad "BY14" smd circle
			(at -26.844498 0.649732 270)
			(size 0.4318 0.4318)
			(layers "F.Cu" "F.Mask" "F.Paste")
			(net "P5E_CPU1_PE1_TX_DP<7>")
		)
		(pad "BY16" smd circle
			(at -25.216612 0.649732 270)
			(size 0.4318 0.4318)
			(layers "F.Cu" "F.Mask" "F.Paste")
			(net "GND")
		)
		(pad "BY18" smd circle
			(at -23.58898 0.649732 270)
			(size 0.4318 0.4318)
			(layers "F.Cu" "F.Mask" "F.Paste")
			(net "TP_DMI_CPU1_PCH_TX_DP<1>")
		)
		(pad "BY20" smd circle
			(at -21.961094 0.649732 270)
			(size 0.4318 0.4318)
			(layers "F.Cu" "F.Mask" "F.Paste")
			(net "GND")
		)
		(pad "BY22" smd circle
			(at -20.333462 0.649732 270)
			(size 0.4318 0.4318)
			(layers "F.Cu" "F.Mask" "F.Paste")
			(net "I3C_SPD_DDRABCD_CPU1_SDA")
		)
	)
)
